FILE_TYPE = CONNECTIVITY;
{Allegro Design Entry HDL 17.2-2016 S081 (4005846) 1/11/2022}
"PAGE_NUMBER" = 280;
0"NC";
1"PVCCFA_EHV_CPU1\g";
2"SW_P12V_PVCCINFAON_CPU1_FLT\g";
3"PVCCFA_EHV_CPU1_VDD1\g";
4"P3V3\g";
5"P5V\g";
6"GND\g";
7"GND\g";
8"GND\g";
9"GND\g";
10"GND\g";
11"GND\g";
12"PVCCFA_EHV_CPU1_LSET1";
13"SW_PVCCFA_EHV_CPU1_BOOT1"CDS_PHYS_NET_NAME"SW_PVCCFA_EHV_CPU1_BOOT1";
14"SW_PVCCFA_EHV_CPU1_BOOT1_R";
15"SW_PVCCFA_EHV_CPU1_BOOTR1"CDS_PHYS_NET_NAME"SW_PVCCFA_EHV_CPU1_BOOTR1";
16"PVCCFA_EHV_CPU1_NC1";
17"SW_PVCCFA_EHV_CPU1_SW1";
18"PVCCFA_EHV_CPU1_FAULT";
19"PVCCFA_EHV_CPU1_PVCC";
20"PVCCFA_EHV_CPU1_VDD1";
21"PVCCFA_EHV_CPU1_BTSEN";
22"PVCCFA_EHV_CPU1_BPWM1";
23"PVCCFA_EHV_CPU1_BCSP1";
24"PVCCFA_EHV_CPU1_NC2";
25"PVCCINFAON_CPU1_VREF"CDS_PHYS_NET_NAME"PVCCINFAON_CPU1_VREF";
%"Q_RES"
"2","(-6775,8600)","2","pure_quanta","I1";
;
PART_NUMBER"CS28872FB01"
VALUE"8.87K"
TOLERANCE"1%"
MATERIAL"EMPTY"
PACK_TYPE"0402LF"
WATTAGE"1/16W"
LOCATION"PR1728"
CDS_LIB"pure_quanta"
$SEC"1"
CDS_SEC"1";
"A"
$PN"1"12;
"B"
$PN"2"11;
%"Q_CAP"
"1","(-6100,9650)","0","pure_quanta","I11";
;
PART_NUMBER"CH5222KEB01"
TOLERANCE"10%"
VOLTAGE"10V"
VALUE"2.2UF"
MATERIAL"X6S"
PACK_TYPE"C0402"
LOCATION"PC428"
CDS_LIB"pure_quanta"
LOCATION"PC428"
$SEC"1"
CDS_SEC"1";
"B"
$PN"2"9;
"A"
$PN"1"20;
%"UNIVERSAL_GND"
"1","(-6100,9400)","0","logical_power","I12";
;
CDS_LIB"logical_power"
HDL_POWER"GND";
"A"9;
%"Q_RES"
"1","(-5650,9600)","1","pure_quanta","I13";
;
PART_NUMBER"CS00002JB13"
VALUE"0"
TOLERANCE"5%"
MATERIAL"EMPTY"
LOCATION"PR4248"
PACK_TYPE"0402LF"
WATTAGE"1/16W"
CDS_LIB"pure_quanta"
$SEC"1"
CDS_SEC"1";
"B"
$PN"2"20;
"A"
$PN"1"24;
%"RAA2213404GNPHB0"
"1","(-4600,9225)","0","pure_quanta","I14";
;
PART_NUMBER"AL221340002"
PART_TYPE"SMLF"
MATERIAL"IC"
VALUE"RAA2213404GNP#HB0"
LOCATION"PU49"
NEEDS_NO_SIZE"TRUE"
CDS_LMAN_SYM_OUTLINE"-275,675,275,-675"
CDS_LIB"pure_quanta"
$SEC"1"
CDS_SEC"1";
"LGCTRL"
$PN"3"16;
"GL1"
$PN"5"12;
"NC1"
$PN"22"24;
"GND3"
$PN"26"8;
"FAULT# \B"
$PN"2"18;
"SW"
$PN"8_12"17;
"GL2"
$PN"27"0;
"GND1"
$PN"6_7-13_15-29"8;
"IMON"
$PN"25"23;
"TMON"
$PN"1"21;
"VCC"
$PN"4"20;
"PHASE"
$PN"19"15;
"VIN"
$PN"16_18-28"2;
"BOOT"
$PN"20"13;
"GND2"
$PN"23"8;
"REFIN"
$PN"24"25;
"PWM"
$PN"21"22;
%"Q_RES"
"2","(-6100,10050)","0","pure_quanta","I15";
;
PART_NUMBER"CS-2202FB01"
PACK_TYPE"0402LF"
WATTAGE"1/16W"
VALUE"2.2"
TOLERANCE"1%"
MATERIAL"CHIP"
LOCATION"PR250"
CDS_LIB"pure_quanta"
LOCATION"PR250"
$SEC"1"
CDS_SEC"1";
"A"
$PN"1"19;
"B"
$PN"2"20;
%"Q_RES"
"2","(-5750,10675)","0","pure_quanta","I16";
;
PART_NUMBER"CS00002JB13"
PACK_TYPE"0402LF"
VALUE"0"
TOLERANCE"5%"
MATERIAL"EMPTY"
WATTAGE"1/16W"
LOCATION"PR699"
CDS_LIB"pure_quanta"
$SEC"1"
CDS_SEC"1";
"A"
$PN"1"4;
"B"
$PN"2"19;
%"VCC15"
"1","(-5750,10900)","0","logical_power","I17";
;
HDL_POWER"P3V3"
CDS_LIB"logical_power";
"A"4;
%"Q_RES"
"1","(-3125,8700)","0","pure_quanta","I18";
;
PART_NUMBER"CS00002JB13"
WATTAGE"1/16W"
TOLERANCE"5%"
VALUE"0"
PACK_TYPE"0402LF"
MATERIAL"EMPTY"
LOCATION"PR4249"
CDS_LIB"pure_quanta"
$SEC"1"
CDS_SEC"1";
"B"
$PN"2"8;
"A"
$PN"1"18;
%"UNIVERSAL_GND"
"1","(-2525,8475)","0","logical_power","I19";
;
CDS_LIB"logical_power"
HDL_POWER"GND";
"A"8;
%"UNIVERSAL_GND"
"1","(-6775,8375)","0","logical_power","I2";
;
CDS_LIB"logical_power"
HDL_POWER"GND";
"A"11;
%"Q_RES"
"1","(-3025,8900)","0","pure_quanta","I20";
;
PART_NUMBER"CS00002JB13"
VALUE"0"
PACK_TYPE"0402LF"
TOLERANCE"5%"
WATTAGE"1/16W"
MATERIAL"CHIP"
LOCATION"PR1799"
CDS_LIB"pure_quanta"
$SEC"1"
CDS_SEC"1";
"B"
$PN"2"3;
"A"
$PN"1"16;
%"VCC15"
"1","(-2600,9050)","0","logical_power","I21";
;
HDL_POWER"PVCCFA_EHV_CPU1_VDD1"
CDS_LIB"logical_power";
"A"3;
%"Q_CAP"
"1","(-2450,9475)","2","pure_quanta","I22";
;
PART_NUMBER"CH4106K1B01"
VOLTAGE"50V"
TOLERANCE"10%"
MATERIAL"X7R"
VALUE"100NF"
PACK_TYPE"C0402"
LOCATION"PC431"
CDS_LIB"pure_quanta"
$SEC"1"
CDS_SEC"1";
"B"
$PN"2"15;
"A"
$PN"1"14;
%"Q_INDUCTOR"
"1","(-2225,9225)","0","pure_quanta","I23";
;
PART_NUMBER"CV+30Y0KZ05"
MATERIAL"IND"
PACK_TYPE"SMLF"
VALUE"300NH/33A"
LOCATION"PL20"
NEEDS_NO_SIZE"TRUE"
CDS_LIB"pure_quanta"
$SEC"1"
CDS_SEC"1";
"1"
$PN"1"17;
"2"
$PN"2"1;
%"Q_CAP"
"1","(-3775,10100)","0","pure_quanta","I24";
;
PART_NUMBER"TMP_QCH2336K1B12"
VOLTAGE"50V"
VALUE"3300PF"
TOLERANCE"10%"
MATERIAL"X7R"
PACK_TYPE"0402"
LOCATION"PC429"
CDS_LIB"pure_quanta"
LOCATION"PC429"
$SEC"1"
CDS_SEC"1";
"B"
$PN"2"7;
"A"
$PN"1"2;
%"Q_RES"
"1","(-3250,9650)","0","pure_quanta","I25";
;
PART_NUMBER"CS-3302FB01"
TOLERANCE"1%"
WATTAGE"1/16W"
PACK_TYPE"0402LF"
MATERIAL"CHIP"
VALUE"3.3"
LOCATION"PR1798"
CDS_LIB"pure_quanta"
$SEC"1"
CDS_SEC"1";
"B"
$PN"2"14;
"A"
$PN"1"13;
%"Q_CAP"
"1","(-3325,10100)","0","pure_quanta","I26";
;
PART_NUMBER"CH5103KEB01"
MATERIAL"X6S"
TOLERANCE"10%"
VOLTAGE"16V"
PACK_TYPE"C0402"
VALUE"1UF"
LOCATION"PC430"
CDS_LIB"pure_quanta"
LOCATION"PC430"
$SEC"1"
CDS_SEC"1";
"B"
$PN"2"7;
"A"
$PN"1"2;
%"Q_CAP"
"1","(-2950,10100)","0","pure_quanta","I27";
;
PART_NUMBER"CH6223MEA01"
VALUE"22UF"
PACK_TYPE"C0805"
MATERIAL"X6S"
VOLTAGE"16V"
TOLERANCE"20%"
LOCATION"PC432"
CDS_LIB"pure_quanta"
LOCATION"PC432"
$SEC"1"
CDS_SEC"1";
"B"
$PN"2"7;
"A"
$PN"1"2;
%"Q_CAP"
"1","(-2575,10100)","0","pure_quanta","I28";
;
PART_NUMBER"CH6223MEA01"
PACK_TYPE"C0805"
VOLTAGE"16V"
VALUE"22UF"
MATERIAL"X6S"
TOLERANCE"20%"
LOCATION"PC433"
CDS_LIB"pure_quanta"
LOCATION"PC433"
$SEC"1"
CDS_SEC"1";
"B"
$PN"2"7;
"A"
$PN"1"2;
%"Q_CAP"
"1","(-2000,9000)","0","pure_quanta","I29";
;
PART_NUMBER"CH4106K1B01"
TOLERANCE"10%"
MATERIAL"X7R"
VALUE"100NF"
VOLTAGE"50V"
PACK_TYPE"C0402"
LOCATION"PC434"
CDS_LIB"pure_quanta"
LOCATION"PC434"
$SEC"1"
CDS_SEC"1";
"B"
$PN"2"6;
"A"
$PN"1"1;
%"UNIVERSAL_GND"
"1","(-7025,8925)","0","logical_power","I3";
;
CDS_LIB"logical_power"
HDL_POWER"GND";
"A"10;
%"Q_CAP"
"1","(-1600,9000)","0","pure_quanta","I30";
;
PART_NUMBER"CH622KMEA03"
VALUE"22UF"
VOLTAGE"4V"
MATERIAL"X6S"
PACK_TYPE"C0805"
TOLERANCE"20%"
LOCATION"PC435"
CDS_LIB"pure_quanta"
LOCATION"PC435"
$SEC"1"
CDS_SEC"1";
"B"
$PN"2"6;
"A"
$PN"1"1;
%"Q_CAP"
"1","(-1175,9000)","0","pure_quanta","I31";
;
PART_NUMBER"CH622KMEA03"
VALUE"22UF"
VOLTAGE"4V"
MATERIAL"X6S"
PACK_TYPE"C0805"
TOLERANCE"20%"
LOCATION"PC437"
CDS_LIB"pure_quanta"
LOCATION"PC437"
$SEC"1"
CDS_SEC"1";
"B"
$PN"2"6;
"A"
$PN"1"1;
%"Q_CAPP"
"1","(-775,9000)","0","pure_quanta","I32";
;
PART_NUMBER"CC7560JMD16"
VOLTAGE"2.5V"
MATERIAL"OSCON"
TOLERANCE"20%"
VALUE"560UF"
PACK_TYPE"THLF"
LOCATION"PC2199"
CDS_LIB"pure_quanta"
$SEC"1"
CDS_SEC"1";
"A"
$PN"1"1;
"B"
$PN"2"6;
%"Q_CAPP"
"1","(-350,9000)","0","pure_quanta","I33";
;
PART_NUMBER"CH733LY8802"
TOLERANCE"+10/-35%"
MATERIAL"SPCAP"
VALUE"330UF"
PACK_TYPE"SMLF"
VOLTAGE"2.5V"
LOCATION"PC1930"
CDS_LIB"pure_quanta"
$SEC"1"
CDS_SEC"1";
"A"
$PN"1"1;
"B"
$PN"2"6;
%"UNIVERSAL_GND"
"1","(-1975,9675)","0","logical_power","I34";
;
CDS_LIB"logical_power"
HDL_POWER"GND";
"A"7;
%"VCC15"
"1","(-1975,10475)","0","logical_power","I35";
;
HDL_POWER"SW_P12V_PVCCINFAON_CPU1_FLT"
CDS_LIB"logical_power";
"A"2;
%"UNIVERSAL_GND"
"1","(125,8625)","0","logical_power","I36";
;
CDS_LIB"logical_power"
HDL_POWER"GND";
"A"6;
%"Q_RES"
"2","(125,9000)","0","pure_quanta","I37";
;
PART_NUMBER"CS14992FB06"
VALUE"499"
TOLERANCE"1%"
WATTAGE"1/16W"
MATERIAL"CHIP"
PACK_TYPE"0402LF"
LOCATION"PR4250"
CDS_LIB"pure_quanta"
BOM_COST"VR_PCH"
$SEC"1"
CDS_SEC"1";
"A"
$PN"1"1;
"B"
$PN"2"6;
%"VCC15"
"1","(125,9350)","0","logical_power","I38";
;
HDL_POWER"PVCCFA_EHV_CPU1"
CDS_LIB"logical_power";
"A"1;
%"Q_RES"
"2","(-6575,10675)","0","pure_quanta","I4";
;
PART_NUMBER"CS00002JB13"
PACK_TYPE"0402LF"
VALUE"0"
TOLERANCE"5%"
MATERIAL"CHIP"
WATTAGE"1/16W"
LOCATION"PR678"
CDS_LIB"pure_quanta"
$SEC"1"
CDS_SEC"1";
"A"
$PN"1"5;
"B"
$PN"2"19;
%"VCC15"
"1","(-6575,10900)","0","logical_power","I5";
;
HDL_POWER"P5V"
CDS_LIB"logical_power";
"A"5;
%"Q_CAP"
"2","(-5925,9000)","0","pure_quanta","I9";
;
PART_NUMBER"CH4104K1B00"
TOLERANCE"10%"
VOLTAGE"25V"
PACK_TYPE"0402"
MATERIAL"X7R"
VALUE"0.1UF"
LOCATION"PC1366"
CDS_LIB"pure_quanta"
$SEC"1"
CDS_SEC"1";
"A"
$PN"1"10;
"B"
$PN"2"25;
END.
